#ISCELL
  mstr_misc dns *
  *
#ISCELL
  mstr_symbols intel_corp_bpage *
  *
#ISCELL
  mstr_standard offpage *
  page208_i1
#ISCELL
  mstr_symbols gnd *
  page208_i10
#CELL
  mstr_discrete cap *
  page208_i104
#CELL
  mstr_discrete cap *
  page208_i105
#CELL
  mstr_discrete res *
  page208_i108
#CELL
  mstr_discrete res *
  page208_i109
#CELL
  mstr_discrete res *
  page208_i114
#CELL
  mstr_discrete res *
  page208_i115
#CELL
  w_hdl ind-120nh-30-gp *
  page208_i116
#CELL
  w_hdl ind-120nh-30-gp *
  page208_i117
#CELL
  w_hdl sc1u10v2kx-4-gp *
  page208_i118
#CELL
  w_hdl sc1u10v2kx-4-gp *
  page208_i119
#CELL
  mstr_discrete capp *
  page208_i12
#CELL
  w_hdl 1r3f-gp *
  page208_i120
#CELL
  w_hdl 1r3f-gp *
  page208_i121
#ISCELL
  mstr_symbols gnd *
  page208_i13
#CELL
  mstr_discrete capp *
  page208_i14
#ISCELL
  mstr_standard offpage *
  page208_i16
#ISCELL
  mstr_standard offpage *
  page208_i17
#ISCELL
  mstr_symbols pvccin_cpu1 *
  page208_i18
#ISCELL
  mstr_symbols gnd *
  page208_i21
#CELL
  dev_discrete cap_a *
  page208_i22
#ISCELL
  mstr_symbols gnd *
  page208_i23
#CELL
  mstr_discrete capp *
  page208_i24
#CELL
  mstr_discrete capp *
  page208_i25
#CELL
  mstr_discrete capp *
  page208_i26
#CELL
  mstr_discrete ir354xx *
  page208_i27
#CELL
  mstr_discrete capp *
  page208_i28
#ISCELL
  mstr_symbols pvccin_cpu1 *
  page208_i29
#ISCELL
  mstr_standard offpage *
  page208_i3
#CELL
  mstr_discrete capp *
  page208_i30
#ISCELL
  mstr_symbols gnd *
  page208_i33
#ISCELL
  mstr_symbols vcc_core *
  page208_i37
#CELL
  mstr_discrete cap *
  page208_i38
#CELL
  mstr_discrete cap *
  page208_i40
#CELL
  mstr_discrete cap *
  page208_i43
#CELL
  dev_discrete cap_a *
  page208_i44
#CELL
  mstr_discrete cap *
  page208_i45
#CELL
  mstr_discrete cap *
  page208_i46
#CELL
  mstr_discrete cap *
  page208_i48
#CELL
  mstr_discrete cap *
  page208_i50
#CELL
  dev_discrete cap_a *
  page208_i51
#CELL
  mstr_discrete cap *
  page208_i52
#CELL
  mstr_discrete cap *
  page208_i53
#CELL
  mstr_discrete cap *
  page208_i54
#CELL
  mstr_discrete cap *
  page208_i55
#ISCELL
  mstr_standard offpage *
  page208_i56
#ISCELL
  mstr_symbols gnd *
  page208_i57
#CELL
  mstr_discrete cap *
  page208_i58
#CELL
  mstr_discrete cap *
  page208_i59
#CELL
  mstr_discrete cap *
  page208_i60
#ISCELL
  mstr_standard offpage *
  page208_i61
#ISCELL
  mstr_symbols vcc_core *
  page208_i62
#ISCELL
  mstr_symbols gnd *
  page208_i63
#ISCELL
  mstr_symbols p5v_stby *
  page208_i64
#ISCELL
  mstr_symbols p5v_stby *
  page208_i65
#CELL
  dev_discrete cap_a *
  page208_i66
#CELL
  dev_discrete cap_a *
  page208_i67
#CELL
  mstr_discrete res *
  page208_i7
#ISCELL
  mstr_standard offpage *
  page208_i70
#CELL
  mstr_discrete ir354xx *
  page208_i71
#ISCELL
  mstr_standard offpage *
  page208_i72
#CELL
  mstr_discrete res *
  page208_i75
#CELL
  mstr_discrete res *
  page208_i76
#ISCELL
  mstr_symbols gnd *
  page208_i77
#ISCELL
  mstr_symbols gnd *
  page208_i78
#ISCELL
  mstr_symbols gnd *
  page208_i79
#ISCELL
  mstr_symbols pvccin_cpu1 *
  page208_i8
#CELL
  dev_discrete cap_a *
  page208_i80
#CELL
  mstr_discrete cap *
  page208_i82
#ISCELL
  mstr_symbols gnd *
  page208_i83
#ISCELL
  mstr_symbols gnd *
  page208_i85
#CELL
  dev_discrete cap_a *
  page208_i87
#ISCELL
  mstr_symbols gnd *
  page208_i88
#CELL
  dev_discrete cap_a *
  page208_i9
#CELL
  mstr_discrete cap *
  page208_i90
#ISCELL
  mstr_symbols gnd *
  page208_i91
#ISCELL
  mstr_symbols gnd *
  page208_i93
